(kicad_pcb
	(version 20241229)
	(generator "pcbnew")
	(generator_version "9.0")
	(general
		(thickness 1.6)
		(legacy_teardrops no)
	)
	(paper "A4")
	(title_block
		(title "OCuLink to PCIe adapter")
		(date "2025-06-18")
		(rev "1.0.0")
		(company "Antmicro Ltd")
		(comment 1 "www.antmicro.com")
		(comment 9 "footprints 63-67 of 159")
	)
	(layers
		(0 "F.Cu" signal)
		(4 "In1.Cu" signal)
		(6 "In2.Cu" signal)
		(2 "B.Cu" signal)
		(9 "F.Adhes" user "F.Adhesive")
		(11 "B.Adhes" user "B.Adhesive")
		(13 "F.Paste" user)
		(15 "B.Paste" user)
		(5 "F.SilkS" user "F.Silkscreen")
		(7 "B.SilkS" user "B.Silkscreen")
		(1 "F.Mask" user)
		(3 "B.Mask" user)
		(17 "Dwgs.User" user "User.Drawings")
		(19 "Cmts.User" user "User.Comments")
		(21 "Eco1.User" user "User.Eco1")
		(23 "Eco2.User" user "User.Eco2")
		(25 "Edge.Cuts" user)
		(27 "Margin" user)
		(31 "F.CrtYd" user "F.Courtyard")
		(29 "B.CrtYd" user "B.Courtyard")
		(35 "F.Fab" user)
		(33 "B.Fab" user)
	)
	(footprint "antmicro-footprints:R_0402_1005Metric"
		(layer "F.Cu")
		(at 118.2 112.1 180)
		(descr "Resistor SMD 0402")
		(tags "resistor SMD 0402")
		(property "Reference" "R3"
			(at -0.8 1.5 180)
			(layer "F.SilkS")
			(effects
				(font
					(size 0.7 0.7)
					(thickness 0.15)
				)
				(justify right top)
			)
		)
		(property "Value" "R_0R_0402"
			(at -1.011843 1.772046 0)
			(layer "F.Fab")
			(effects
				(font
					(size 0.7 0.7)
					(thickness 0.15)
				)
				(justify right top)
			)
		)
		(property "Datasheet" "https://industrial.panasonic.com/cdbs/www-data/pdf/RDA0000/AOA0000C301.pdf"
			(at 0 0 0)
			(layer "F.Fab")
			(hide yes)
			(effects
				(font
					(size 1.27 1.27)
					(thickness 0.15)
				)
			)
		)
		(property "Description" "SMD Chip Resistor, Jumper, 0 ohm, 100 mW, 0402 [1005 Metric], Thick Film, General Purpose"
			(at 0 0 0)
			(layer "F.Fab")
			(hide yes)
			(effects
				(font
					(size 1.27 1.27)
					(thickness 0.15)
				)
			)
		)
		(property "MPN" "ERJ2GE0R00X"
			(at 0 0 180)
			(unlocked yes)
			(layer "F.Fab")
			(hide yes)
			(effects
				(font
					(size 1 1)
					(thickness 0.15)
				)
			)
		)
		(property "Manufacturer" "Panasonic"
			(at 0 0 180)
			(unlocked yes)
			(layer "F.Fab")
			(hide yes)
			(effects
				(font
					(size 1 1)
					(thickness 0.15)
				)
			)
		)
		(property "License" "Apache-2.0"
			(at 0 0 180)
			(unlocked yes)
			(layer "F.Fab")
			(hide yes)
			(effects
				(font
					(size 1 1)
					(thickness 0.15)
				)
			)
		)
		(property "Author" "Antmicro"
			(at 0 0 180)
			(unlocked yes)
			(layer "F.Fab")
			(hide yes)
			(effects
				(font
					(size 1 1)
					(thickness 0.15)
				)
			)
		)
		(property "Val" "0R"
			(at 0 0 180)
			(unlocked yes)
			(layer "F.Fab")
			(hide yes)
			(effects
				(font
					(size 1 1)
					(thickness 0.15)
				)
			)
		)
		(property "Tolerance" ""
			(at 0 0 180)
			(unlocked yes)
			(layer "F.Fab")
			(hide yes)
			(effects
				(font
					(size 1 1)
					(thickness 0.15)
				)
			)
		)
		(property "Current" "1A"
			(at 0 0 180)
			(unlocked yes)
			(layer "F.Fab")
			(hide yes)
			(effects
				(font
					(size 1 1)
					(thickness 0.15)
				)
			)
		)
		(sheetname "/PCIe-connector/")
		(sheetfile "pcie-connector.kicad_sch")
		(attr smd)
		(fp_rect
			(start -0.925 -0.47)
			(end 0.925 0.47)
			(stroke
				(width 0.05)
				(type default)
			)
			(fill no)
			(layer "F.CrtYd")
		)
		(fp_rect
			(start -0.5 -0.25)
			(end 0.5 0.25)
			(stroke
				(width 0.15)
				(type solid)
			)
			(fill no)
			(layer "F.Fab")
		)
		(fp_text user "Author: Antmicro"
			(at -0.95 4.169 0)
			(layer "F.Fab")
			(effects
				(font
					(size 0.7 0.7)
					(thickness 0.15)
				)
				(justify right top)
			)
		)
		(fp_text user "License: Apache-2.0"
			(at -0.949999 5.169 0)
			(layer "F.Fab")
			(effects
				(font
					(size 0.7 0.7)
					(thickness 0.15)
				)
				(justify right top)
			)
		)
		(fp_text user "${REFERENCE}"
			(at 0 0 0)
			(layer "F.Fab")
			(effects
				(font
					(size 0.7 0.7)
					(thickness 0.15)
				)
				(justify right top)
			)
		)
		(pad "1" smd roundrect
			(at -0.48 0 180)
			(size 0.59 0.64)
			(layers "F.Cu" "F.Mask" "F.Paste")
			(roundrect_rratio 0.25)
			(net 134 "+3V3")
			(pintype "passive")
		)
		(pad "2" smd roundrect
			(at 0.48 0 180)
			(size 0.59 0.64)
			(layers "F.Cu" "F.Mask" "F.Paste")
			(roundrect_rratio 0.25)
			(net 83 "/PCIe-connector/3V3_PCIe_AUX")
			(pintype "passive")
		)
	)
	(footprint "antmicro-footprints:R_0402_1005Metric"
		(layer "F.Cu")
		(at 120.5 130.8)
		(descr "Resistor SMD 0402")
		(tags "resistor SMD 0402")
		(property "Reference" "R10"
			(at -3.3 0.4 180)
			(layer "F.SilkS")
			(effects
				(font
					(size 0.7 0.7)
					(thickness 0.15)
				)
				(justify left bottom)
			)
		)
		(property "Value" "R_15k_0402"
			(at -1.011843 1.772046 0)
			(layer "F.Fab")
			(effects
				(font
					(size 0.7 0.7)
					(thickness 0.15)
				)
				(justify left bottom)
			)
		)
		(property "Datasheet" "https://www.bourns.com/docs/product-datasheets/cr.pdf"
			(at 0 0 0)
			(layer "F.Fab")
			(hide yes)
			(effects
				(font
					(size 1.27 1.27)
					(thickness 0.15)
				)
			)
		)
		(property "Description" "SMD Chip Resistor, 15 kohm, ± 1%, 62.5 mW, 0402 [1005 Metric], Thick Film, General Purpose"
			(at 0 0 0)
			(layer "F.Fab")
			(hide yes)
			(effects
				(font
					(size 1.27 1.27)
					(thickness 0.15)
				)
			)
		)
		(property "MPN" "CR0402-FX-1502GLF"
			(at 0 0 0)
			(unlocked yes)
			(layer "F.Fab")
			(hide yes)
			(effects
				(font
					(size 1 1)
					(thickness 0.15)
				)
			)
		)
		(property "Manufacturer" "Bourns"
			(at 0 0 0)
			(unlocked yes)
			(layer "F.Fab")
			(hide yes)
			(effects
				(font
					(size 1 1)
					(thickness 0.15)
				)
			)
		)
		(property "License" "Apache-2.0"
			(at 0 0 0)
			(unlocked yes)
			(layer "F.Fab")
			(hide yes)
			(effects
				(font
					(size 1 1)
					(thickness 0.15)
				)
			)
		)
		(property "Author" "Antmicro"
			(at 0 0 0)
			(unlocked yes)
			(layer "F.Fab")
			(hide yes)
			(effects
				(font
					(size 1 1)
					(thickness 0.15)
				)
			)
		)
		(property "Val" "15k"
			(at 0 0 0)
			(unlocked yes)
			(layer "F.Fab")
			(hide yes)
			(effects
				(font
					(size 1 1)
					(thickness 0.15)
				)
			)
		)
		(property "Tolerance" "1%"
			(at 0 0 0)
			(unlocked yes)
			(layer "F.Fab")
			(hide yes)
			(effects
				(font
					(size 1 1)
					(thickness 0.15)
				)
			)
		)
		(sheetname "/Power/")
		(sheetfile "power.kicad_sch")
		(attr smd)
		(fp_rect
			(start -0.925 -0.47)
			(end 0.925 0.47)
			(stroke
				(width 0.05)
				(type default)
			)
			(fill no)
			(layer "F.CrtYd")
		)
		(fp_rect
			(start -0.5 -0.25)
			(end 0.5 0.25)
			(stroke
				(width 0.15)
				(type solid)
			)
			(fill no)
			(layer "F.Fab")
		)
		(fp_text user "Author: Antmicro"
			(at -0.95 4.169 0)
			(layer "F.Fab")
			(effects
				(font
					(size 0.7 0.7)
					(thickness 0.15)
				)
				(justify left bottom)
			)
		)
		(fp_text user "License: Apache-2.0"
			(at -0.949999 5.169 0)
			(layer "F.Fab")
			(effects
				(font
					(size 0.7 0.7)
					(thickness 0.15)
				)
				(justify left bottom)
			)
		)
		(fp_text user "${REFERENCE}"
			(at 0 0 0)
			(layer "F.Fab")
			(effects
				(font
					(size 0.7 0.7)
					(thickness 0.15)
				)
				(justify left bottom)
			)
		)
		(pad "1" smd roundrect
			(at -0.48 0)
			(size 0.59 0.64)
			(layers "F.Cu" "F.Mask" "F.Paste")
			(roundrect_rratio 0.25)
			(net 66 "GND")
			(pintype "passive")
		)
		(pad "2" smd roundrect
			(at 0.48 0)
			(size 0.59 0.64)
			(layers "F.Cu" "F.Mask" "F.Paste")
			(roundrect_rratio 0.25)
			(net 108 "/Power/3V3_FB")
			(pintype "passive")
		)
	)
	(footprint "antmicro-footprints:QFN-2L_1.6x1x0.55mm"
		(layer "F.Cu")
		(at 140.5 43.2 90)
		(property "Reference" "D21"
			(at 0.8 0.9 90)
			(layer "F.SilkS")
			(effects
				(font
					(size 0.7 0.7)
					(thickness 0.15)
				)
				(justify right top)
			)
		)
		(property "Value" "ESDA25P35-1U1M"
			(at 0 1.700001 90)
			(layer "F.Fab")
			(effects
				(font
					(size 0.7 0.7)
					(thickness 0.15)
				)
				(justify left bottom)
			)
		)
		(property "Datasheet" "https://www.st.com/resource/en/datasheet/esda25p35-1u1m.pdf"
			(at 0 0 90)
			(layer "F.Fab")
			(hide yes)
			(effects
				(font
					(size 1.27 1.27)
					(thickness 0.15)
				)
			)
		)
		(property "Description" "Unidirectional TVS, 30 kV, QFN-2L, 22 V, 195 pF"
			(at 0 0 90)
			(layer "F.Fab")
			(hide yes)
			(effects
				(font
					(size 1.27 1.27)
					(thickness 0.15)
				)
			)
		)
		(property "MPN" "ESDA25P35-1U1M"
			(at 0 0 90)
			(unlocked yes)
			(layer "F.Fab")
			(hide yes)
			(effects
				(font
					(size 1 1)
					(thickness 0.15)
				)
			)
		)
		(property "Manufacturer" "STMicroelectronics"
			(at 0 0 90)
			(unlocked yes)
			(layer "F.Fab")
			(hide yes)
			(effects
				(font
					(size 1 1)
					(thickness 0.15)
				)
			)
		)
		(property "Author" "Antmicro"
			(at 0 0 90)
			(unlocked yes)
			(layer "F.Fab")
			(hide yes)
			(effects
				(font
					(size 1 1)
					(thickness 0.15)
				)
			)
		)
		(property "License" "Apache-2.0"
			(at 0 0 90)
			(unlocked yes)
			(layer "F.Fab")
			(hide yes)
			(effects
				(font
					(size 1 1)
					(thickness 0.15)
				)
			)
		)
		(sheetname "/USB-PD/")
		(sheetfile "usb-pd.kicad_sch")
		(attr smd)
		(fp_line
			(start 0.23 -0.45)
			(end -0.23 -0.45)
			(stroke
				(width 0.15)
				(type solid)
			)
			(layer "F.SilkS")
		)
		(fp_line
			(start -1.2 -0.4)
			(end -1.2 0.4)
			(stroke
				(width 0.15)
				(type solid)
			)
			(layer "F.SilkS")
		)
		(fp_line
			(start 0.23 0.45)
			(end -0.23 0.45)
			(stroke
				(width 0.15)
				(type solid)
			)
			(layer "F.SilkS")
		)
		(fp_rect
			(start 1.25 0.65)
			(end -1.25 -0.65)
			(stroke
				(width 0.05)
				(type solid)
			)
			(fill no)
			(layer "F.CrtYd")
		)
		(fp_line
			(start 0.201 -0.202)
			(end -0.101 0)
			(stroke
				(width 0.15)
				(type solid)
			)
			(layer "F.Fab")
		)
		(fp_line
			(start -0.199 -0.202)
			(end -0.199 0.1)
			(stroke
				(width 0.15)
				(type solid)
			)
			(layer "F.Fab")
		)
		(fp_line
			(start 0.599 0)
			(end 0.201 0)
			(stroke
				(width 0.15)
				(type solid)
			)
			(layer "F.Fab")
		)
		(fp_line
			(start 0.201 0)
			(end 0.201 -0.202)
			(stroke
				(width 0.15)
				(type solid)
			)
			(layer "F.Fab")
		)
		(fp_line
			(start -0.101 0)
			(end 0.201 0.2)
			(stroke
				(width 0.15)
				(type solid)
			)
			(layer "F.Fab")
		)
		(fp_line
			(start -0.199 0)
			(end -0.597 0)
			(stroke
				(width 0.15)
				(type solid)
			)
			(layer "F.Fab")
		)
		(fp_line
			(start 0.201 0.2)
			(end 0.201 0)
			(stroke
				(width 0.15)
				(type solid)
			)
			(layer "F.Fab")
		)
		(fp_line
			(start -0.199 0.2)
			(end -0.199 0.1)
			(stroke
				(width 0.15)
				(type solid)
			)
			(layer "F.Fab")
		)
		(fp_rect
			(start 0.848 0.4)
			(end -0.85 -0.402)
			(stroke
				(width 0.15)
				(type solid)
			)
			(fill no)
			(layer "F.Fab")
		)
		(fp_text user "${REFERENCE}"
			(at 0 0 90)
			(layer "F.Fab")
			(effects
				(font
					(size 0.7 0.7)
					(thickness 0.15)
				)
				(justify left bottom)
			)
		)
		(fp_text user "Author: Antmicro"
			(at -1.31 4.769 90)
			(layer "F.Fab")
			(effects
				(font
					(size 0.7 0.7)
					(thickness 0.15)
				)
				(justify left bottom)
			)
		)
		(fp_text user "License: Apache-2.0"
			(at -1.31 5.769 90)
			(layer "F.Fab")
			(effects
				(font
					(size 0.7 0.7)
					(thickness 0.15)
				)
				(justify left bottom)
			)
		)
		(pad "1" smd roundrect
			(at -0.7 0 270)
			(size 0.8 1)
			(layers "F.Cu" "F.Mask" "F.Paste")
			(roundrect_rratio 0.2)
			(net 113 "VBUS")
			(pinfunction "C")
			(pintype "passive")
		)
		(pad "2" smd roundrect
			(at 0.7 0 270)
			(size 0.8 1)
			(layers "F.Cu" "F.Mask" "F.Paste")
			(roundrect_rratio 0.2)
			(net 66 "GND")
			(pinfunction "A")
			(pintype "passive")
		)
	)
	(footprint "antmicro-footprints:C_0805_2012Metric"
		(layer "F.Cu")
		(at 134.5 89.5 90)
		(descr "Capacitor SMD 0805")
		(tags "capacitor SMD 0805")
		(property "Reference" "C22"
			(at 0.3 -3.1 90)
			(layer "F.SilkS")
			(effects
				(font
					(size 0.7 0.7)
					(thickness 0.15)
				)
				(justify left bottom)
			)
		)
		(property "Value" "C_10u_0805_35V"
			(at -2.055717 1.963153 90)
			(layer "F.Fab")
			(effects
				(font
					(size 0.7 0.7)
					(thickness 0.15)
				)
				(justify left bottom)
			)
		)
		(property "Datasheet" "https://www.murata.com/products/productdetail?partno=GRM21BR6YA106KE43%23"
			(at 0 0 90)
			(layer "F.Fab")
			(hide yes)
			(effects
				(font
					(size 1.27 1.27)
					(thickness 0.15)
				)
			)
		)
		(property "Description" "SMD Multilayer Ceramic Capacitor, 10 µF, 35 V, 0805 [2012 Metric], ± 10%, X5R, GRM Series"
			(at 0 0 90)
			(layer "F.Fab")
			(hide yes)
			(effects
				(font
					(size 1.27 1.27)
					(thickness 0.15)
				)
			)
		)
		(property "MPN" "GRM21BR6YA106KE43L"
			(at 0 0 90)
			(unlocked yes)
			(layer "F.Fab")
			(hide yes)
			(effects
				(font
					(size 1 1)
					(thickness 0.15)
				)
			)
		)
		(property "Manufacturer" "Murata"
			(at 0 0 90)
			(unlocked yes)
			(layer "F.Fab")
			(hide yes)
			(effects
				(font
					(size 1 1)
					(thickness 0.15)
				)
			)
		)
		(property "License" "Apache-2.0"
			(at 0 0 90)
			(unlocked yes)
			(layer "F.Fab")
			(hide yes)
			(effects
				(font
					(size 1 1)
					(thickness 0.15)
				)
			)
		)
		(property "Author" "Antmicro"
			(at 0 0 90)
			(unlocked yes)
			(layer "F.Fab")
			(hide yes)
			(effects
				(font
					(size 1 1)
					(thickness 0.15)
				)
			)
		)
		(property "Val" "10u"
			(at 0 0 90)
			(unlocked yes)
			(layer "F.Fab")
			(hide yes)
			(effects
				(font
					(size 1 1)
					(thickness 0.15)
				)
			)
		)
		(property "Voltage" "35V"
			(at 0 0 90)
			(unlocked yes)
			(layer "F.Fab")
			(hide yes)
			(effects
				(font
					(size 1 1)
					(thickness 0.15)
				)
			)
		)
		(property "Dielectric" ""
			(at 0 0 90)
			(unlocked yes)
			(layer "F.Fab")
			(hide yes)
			(effects
				(font
					(size 1 1)
					(thickness 0.15)
				)
			)
		)
		(property "Public" "False"
			(at 0 0 90)
			(unlocked yes)
			(layer "F.Fab")
			(hide yes)
			(effects
				(font
					(size 1 1)
					(thickness 0.15)
				)
			)
		)
		(sheetname "/USB-PD/")
		(sheetfile "usb-pd.kicad_sch")
		(attr smd)
		(fp_line
			(start -0.3 -0.7)
			(end 0.3 -0.7)
			(stroke
				(width 0.15)
				(type solid)
			)
			(layer "F.SilkS")
		)
		(fp_line
			(start -0.3 0.7)
			(end 0.3 0.7)
			(stroke
				(width 0.15)
				(type solid)
			)
			(layer "F.SilkS")
		)
		(fp_rect
			(start 1.95 -0.9)
			(end -1.95 0.9)
			(stroke
				(width 0.05)
				(type default)
			)
			(fill no)
			(layer "F.CrtYd")
		)
		(fp_rect
			(start -0.95 -0.675)
			(end 0.95 0.675)
			(stroke
				(width 0.15)
				(type solid)
			)
			(fill no)
			(layer "F.Fab")
		)
		(fp_text user "Author: Antmicro"
			(at -1.9 5.947 90)
			(layer "F.Fab")
			(effects
				(font
					(size 0.7 0.7)
					(thickness 0.15)
				)
				(justify left bottom)
			)
		)
		(fp_text user "License: Apache-2.0"
			(at -1.9 4.947 90)
			(layer "F.Fab")
			(effects
				(font
					(size 0.7 0.7)
					(thickness 0.15)
				)
				(justify left bottom)
			)
		)
		(fp_text user "${REFERENCE}"
			(at 0 0 90)
			(layer "F.Fab")
			(effects
				(font
					(size 0.7 0.7)
					(thickness 0.15)
				)
				(justify left bottom)
			)
		)
		(pad "1" smd roundrect
			(at -1.1 0 90)
			(size 1.2 1.3)
			(layers "F.Cu" "F.Mask" "F.Paste")
			(roundrect_rratio 0.25)
			(net 66 "GND")
			(pintype "passive")
		)
		(pad "2" smd roundrect
			(at 1.1 0 90)
			(size 1.2 1.3)
			(layers "F.Cu" "F.Mask" "F.Paste")
			(roundrect_rratio 0.25)
			(net 115 "/USB-PD/VCC")
			(pintype "passive")
		)
	)
	(footprint "antmicro-footprints:R_0402_1005Metric"
		(layer "F.Cu")
		(at 134.651 68.05 -90)
		(descr "Resistor SMD 0402")
		(tags "resistor SMD 0402")
		(property "Reference" "R38"
			(at 0.900001 4.6005 90)
			(layer "F.SilkS")
			(effects
				(font
					(size 0.7 0.7)
					(thickness 0.15)
				)
				(justify left bottom)
			)
		)
		(property "Value" "R_10k_0402"
			(at -1.011843 1.772046 90)
			(layer "F.Fab")
			(effects
				(font
					(size 0.7 0.7)
					(thickness 0.15)
				)
				(justify right top)
			)
		)
		(property "Datasheet" "https://www.bourns.com/docs/product-datasheets/cr.pdf"
			(at 0 0 90)
			(layer "F.Fab")
			(hide yes)
			(effects
				(font
					(size 1.27 1.27)
					(thickness 0.15)
				)
			)
		)
		(property "Description" "SMD Chip Resistor, 10 kohm, ± 1%, 62.5 mW, 0402 [1005 Metric], Thick Film, General Purpose"
			(at 0 0 90)
			(layer "F.Fab")
			(hide yes)
			(effects
				(font
					(size 1.27 1.27)
					(thickness 0.15)
				)
			)
		)
		(property "MPN" "CR0402-FX-1002GLF"
			(at 0 0 270)
			(unlocked yes)
			(layer "F.Fab")
			(hide yes)
			(effects
				(font
					(size 1 1)
					(thickness 0.15)
				)
			)
		)
		(property "Manufacturer" "Bourns"
			(at 0 0 270)
			(unlocked yes)
			(layer "F.Fab")
			(hide yes)
			(effects
				(font
					(size 1 1)
					(thickness 0.15)
				)
			)
		)
		(property "License" "Apache-2.0"
			(at 0 0 270)
			(unlocked yes)
			(layer "F.Fab")
			(hide yes)
			(effects
				(font
					(size 1 1)
					(thickness 0.15)
				)
			)
		)
		(property "Author" "Antmicro"
			(at 0 0 270)
			(unlocked yes)
			(layer "F.Fab")
			(hide yes)
			(effects
				(font
					(size 1 1)
					(thickness 0.15)
				)
			)
		)
		(property "Val" "10k"
			(at 0 0 270)
			(unlocked yes)
			(layer "F.Fab")
			(hide yes)
			(effects
				(font
					(size 1 1)
					(thickness 0.15)
				)
			)
		)
		(property "Tolerance" "1%"
			(at 0 0 270)
			(unlocked yes)
			(layer "F.Fab")
			(hide yes)
			(effects
				(font
					(size 1 1)
					(thickness 0.15)
				)
			)
		)
		(sheetname "/USB-PD/")
		(sheetfile "usb-pd.kicad_sch")
		(attr smd)
		(fp_rect
			(start -0.925 -0.47)
			(end 0.925 0.47)
			(stroke
				(width 0.05)
				(type default)
			)
			(fill no)
			(layer "F.CrtYd")
		)
		(fp_rect
			(start -0.5 -0.25)
			(end 0.5 0.25)
			(stroke
				(width 0.15)
				(type solid)
			)
			(fill no)
			(layer "F.Fab")
		)
		(fp_text user "License: Apache-2.0"
			(at -0.949999 5.169 90)
			(layer "F.Fab")
			(effects
				(font
					(size 0.7 0.7)
					(thickness 0.15)
				)
				(justify right top)
			)
		)
		(fp_text user "${REFERENCE}"
			(at 0 0 270)
			(layer "F.Fab")
			(effects
				(font
					(size 0.7 0.7)
					(thickness 0.15)
				)
				(justify left bottom)
			)
		)
		(fp_text user "Author: Antmicro"
			(at -0.95 4.169 90)
			(layer "F.Fab")
			(effects
				(font
					(size 0.7 0.7)
					(thickness 0.15)
				)
				(justify right top)
			)
		)
		(pad "1" smd roundrect
			(at -0.48 0 270)
			(size 0.59 0.64)
			(layers "F.Cu" "F.Mask" "F.Paste")
			(roundrect_rratio 0.25)
			(net 66 "GND")
			(pintype "passive")
		)
		(pad "2" smd roundrect
			(at 0.48 0 270)
			(size 0.59 0.64)
			(layers "F.Cu" "F.Mask" "F.Paste")
			(roundrect_rratio 0.25)
			(net 124 "/USB-PD/FAULT")
			(pintype "passive")
		)
	)
)
